(kicad_pcb
	(version 20260206)
	(generator "pcbnew")
	(generator_version "10.0")
	(general
		(thickness 1.6)
		(legacy_teardrops no)
	)
	(paper "A4")
	(title_block
		(title "12092022_DA0F0TMDCD0_F0T_Management_Board_D_brd_V3_OCP.brd")
		(comment 1 "Grand Teton / footprints 521-527 of 1440")
	)
	(layers
		(0 "F.Cu" signal "TOP")
		(4 "In1.Cu" signal "GND")
		(6 "In2.Cu" signal "IN1")
		(8 "In3.Cu" signal "GND1")
		(10 "In4.Cu" signal "IN2")
		(12 "In5.Cu" signal "VCC")
		(14 "In6.Cu" signal "VCC1")
		(16 "In7.Cu" signal "IN3")
		(18 "In8.Cu" signal "GND2")
		(20 "In9.Cu" signal "IN4")
		(22 "In10.Cu" signal "GND3")
		(2 "B.Cu" signal "BOTTOM")
		(9 "F.Adhes" user "F.Adhesive")
		(11 "B.Adhes" user "B.Adhesive")
		(13 "F.Paste" user "Package Geometry/Pastemask Top")
		(15 "B.Paste" user "Package Geometry/Pastemask Bottom")
		(5 "F.SilkS" user "Ref Des/Silkscreen Top")
		(7 "B.SilkS" user "Ref Des/Silkscreen Bottom")
		(1 "F.Mask" user "Board Geometry/Soldermask Top")
		(3 "B.Mask" user "Board Geometry/Soldermask Bottom")
		(17 "Dwgs.User" user "User.Drawings")
		(19 "Cmts.User" user "User.Comments")
		(21 "Eco1.User" user "User.Eco1")
		(23 "Eco2.User" user "User.Eco2")
		(25 "Edge.Cuts" user "Board Geometry/Outline")
		(27 "Margin" user)
		(31 "F.CrtYd" user "Package Geometry/Place Bound Top")
		(29 "B.CrtYd" user "Package Geometry/Place Bound Bottom")
		(35 "F.Fab" user "Ref Des/Assembly Top")
		(33 "B.Fab" user "Ref Des/Assembly Bottom")
	)
	(footprint ""
		(layer "F.Cu")
		(at 67.900804 -31.191454 -90)
		(property "Reference" "U14"
			(at -2.019046 0.754634 90)
			(unlocked yes)
			(layer "F.SilkS")
			(effects
				(font
					(size 0.7874 0.5842)
					(thickness 0.1524)
				)
				(justify left)
			)
		)
		(property "Value" ""
			(at 0 0 270)
			(layer "F.Fab")
			(effects
				(font
					(size 1.27 1.27)
				)
			)
		)
		(duplicate_pad_numbers_are_jumpers no)
		(fp_line
			(start -1.733296 1.549908)
			(end 1.733296 1.549908)
			(stroke
				(width 0.1524)
				(type default)
			)
			(layer "F.SilkS")
		)
		(fp_line
			(start 1.733296 1.549908)
			(end 1.733296 -1.549908)
			(stroke
				(width 0.1524)
				(type default)
			)
			(layer "F.SilkS")
		)
		(fp_line
			(start 0 -0.889)
			(end -0.660908 -1.549908)
			(stroke
				(width 0.1524)
				(type default)
			)
			(layer "F.SilkS")
		)
		(fp_line
			(start -1.733296 -1.549908)
			(end -1.733296 1.549908)
			(stroke
				(width 0.1524)
				(type default)
			)
			(layer "F.SilkS")
		)
		(fp_line
			(start -0.660908 -1.549908)
			(end -1.733296 -1.549908)
			(stroke
				(width 0.1524)
				(type default)
			)
			(layer "F.SilkS")
		)
		(fp_line
			(start 0.660908 -1.549908)
			(end 0 -0.889)
			(stroke
				(width 0.1524)
				(type default)
			)
			(layer "F.SilkS")
		)
		(fp_line
			(start 1.733296 -1.549908)
			(end 0.660908 -1.549908)
			(stroke
				(width 0.1524)
				(type default)
			)
			(layer "F.SilkS")
		)
		(fp_poly
			(pts
				(xy -2.4384 -1.20396) (xy -2.4384 -0.69596) (xy -1.9304 -0.94996)
			)
			(stroke
				(width 0)
				(type default)
			)
			(fill yes)
			(layer "F.SilkS")
		)
		(fp_line
			(start -0.849884 1.549908)
			(end 0.849884 1.549908)
			(stroke
				(width 0.1)
				(type default)
			)
			(layer "F.Fab")
		)
		(fp_line
			(start 0.849884 1.549908)
			(end 0.849884 -1.549908)
			(stroke
				(width 0.1)
				(type default)
			)
			(layer "F.Fab")
		)
		(fp_line
			(start -0.849884 -1.549908)
			(end -0.849884 1.549908)
			(stroke
				(width 0.1)
				(type default)
			)
			(layer "F.Fab")
		)
		(fp_line
			(start 0.849884 -1.549908)
			(end -0.849884 -1.549908)
			(stroke
				(width 0.1)
				(type default)
			)
			(layer "F.Fab")
		)
		(fp_poly
			(pts
				(xy -2.4384 -1.20396) (xy -2.4384 -0.69596) (xy -1.9304 -0.94996)
			)
			(stroke
				(width 0)
				(type default)
			)
			(fill yes)
			(layer "F.Fab")
		)
		(pad "1" smd rect
			(at -1.199896 -0.94996 180)
			(size 0.5588 0.8128)
			(layers "F.Cu" "F.Mask" "F.Paste")
			(net "P3V3_RGM")
		)
		(pad "2" smd rect
			(at -1.199896 0 180)
			(size 0.5588 0.8128)
			(layers "F.Cu" "F.Mask" "F.Paste")
			(net "GND")
		)
		(pad "3" smd rect
			(at -1.199896 0.94996 180)
			(size 0.5588 0.8128)
			(layers "F.Cu" "F.Mask" "F.Paste")
			(net "TP_U14_FLAG_N")
		)
		(pad "4" smd rect
			(at 1.199896 0.94996 180)
			(size 0.5588 0.8128)
			(layers "F.Cu" "F.Mask" "F.Paste")
			(net "EN_P3V3_RGM_R")
		)
		(pad "5" smd rect
			(at 1.199896 -0.94996 180)
			(size 0.5588 0.8128)
			(layers "F.Cu" "F.Mask" "F.Paste")
			(net "P3V3_AUX")
		)
	)
	(footprint ""
		(layer "F.Cu")
		(at 12.319 -96.52 180)
		(property "Reference" "R638"
			(at 0 0 180)
			(layer "F.SilkS")
			(hide yes)
			(effects
				(font
					(size 1.27 1.27)
				)
			)
		)
		(property "Value" ""
			(at 0 0 180)
			(layer "F.Fab")
			(effects
				(font
					(size 1.27 1.27)
				)
			)
		)
		(duplicate_pad_numbers_are_jumpers no)
		(fp_line
			(start 0.7874 0.4064)
			(end -0.7874 0.4064)
			(stroke
				(width 0.1524)
				(type default)
			)
			(layer "F.SilkS")
		)
		(fp_line
			(start 0.7874 -0.4064)
			(end 0.7874 0.4064)
			(stroke
				(width 0.1524)
				(type default)
			)
			(layer "F.SilkS")
		)
		(fp_line
			(start -0.7874 0.4064)
			(end -0.7874 -0.4064)
			(stroke
				(width 0.1524)
				(type default)
			)
			(layer "F.SilkS")
		)
		(fp_line
			(start -0.7874 -0.4064)
			(end 0.7874 -0.4064)
			(stroke
				(width 0.1524)
				(type default)
			)
			(layer "F.SilkS")
		)
		(fp_line
			(start 0.67945 0.3048)
			(end 0.120396 0.3048)
			(stroke
				(width 0.1)
				(type default)
			)
			(layer "F.Fab")
		)
		(fp_line
			(start 0.67945 -0.3048)
			(end 0.67945 0.3048)
			(stroke
				(width 0.1)
				(type default)
			)
			(layer "F.Fab")
		)
		(fp_line
			(start 0.12065 -0.2794)
			(end 0.12065 -0.3048)
			(stroke
				(width 0.1)
				(type default)
			)
			(layer "F.Fab")
		)
		(fp_line
			(start 0.12065 -0.3048)
			(end 0.67945 -0.3048)
			(stroke
				(width 0.1)
				(type default)
			)
			(layer "F.Fab")
		)
		(fp_line
			(start 0.120396 0.3048)
			(end 0.120396 0.2794)
			(stroke
				(width 0.1)
				(type default)
			)
			(layer "F.Fab")
		)
		(fp_line
			(start 0.120396 0.2794)
			(end -0.12065 0.2794)
			(stroke
				(width 0.1)
				(type default)
			)
			(layer "F.Fab")
		)
		(fp_line
			(start -0.12065 0.3048)
			(end -0.67945 0.3048)
			(stroke
				(width 0.1)
				(type default)
			)
			(layer "F.Fab")
		)
		(fp_line
			(start -0.12065 0.2794)
			(end -0.12065 0.3048)
			(stroke
				(width 0.1)
				(type default)
			)
			(layer "F.Fab")
		)
		(fp_line
			(start -0.12065 -0.2794)
			(end 0.12065 -0.2794)
			(stroke
				(width 0.1)
				(type default)
			)
			(layer "F.Fab")
		)
		(fp_line
			(start -0.12065 -0.305054)
			(end -0.12065 -0.2794)
			(stroke
				(width 0.1)
				(type default)
			)
			(layer "F.Fab")
		)
		(fp_line
			(start -0.67945 0.3048)
			(end -0.67945 -0.305054)
			(stroke
				(width 0.1)
				(type default)
			)
			(layer "F.Fab")
		)
		(fp_line
			(start -0.67945 -0.305054)
			(end -0.12065 -0.305054)
			(stroke
				(width 0.1)
				(type default)
			)
			(layer "F.Fab")
		)
		(pad "1" smd circle
			(at -0.40005 0 180)
			(size 0 0)
			(layers "F.Cu" "F.Mask" "F.Paste")
			(net "RST_BMC_HW_R")
		)
		(pad "2" smd circle
			(at 0.40005 0 180)
			(size 0 0)
			(layers "F.Cu" "F.Mask" "F.Paste")
			(net "RST_BMC_HW")
		)
	)
	(footprint ""
		(layer "F.Cu")
		(at 19.05 -102.743 -90)
		(property "Reference" "R288"
			(at 0 0 270)
			(layer "F.SilkS")
			(hide yes)
			(effects
				(font
					(size 1.27 1.27)
				)
			)
		)
		(property "Value" ""
			(at 0 0 270)
			(layer "F.Fab")
			(effects
				(font
					(size 1.27 1.27)
				)
			)
		)
		(duplicate_pad_numbers_are_jumpers no)
		(fp_line
			(start -0.7874 0.4064)
			(end -0.7874 -0.4064)
			(stroke
				(width 0.1524)
				(type default)
			)
			(layer "F.SilkS")
		)
		(fp_line
			(start 0.7874 0.4064)
			(end -0.7874 0.4064)
			(stroke
				(width 0.1524)
				(type default)
			)
			(layer "F.SilkS")
		)
		(fp_line
			(start -0.7874 -0.4064)
			(end 0.7874 -0.4064)
			(stroke
				(width 0.1524)
				(type default)
			)
			(layer "F.SilkS")
		)
		(fp_line
			(start 0.7874 -0.4064)
			(end 0.7874 0.4064)
			(stroke
				(width 0.1524)
				(type default)
			)
			(layer "F.SilkS")
		)
		(fp_line
			(start -0.67945 0.3048)
			(end -0.67945 -0.305054)
			(stroke
				(width 0.1)
				(type default)
			)
			(layer "F.Fab")
		)
		(fp_line
			(start -0.12065 0.3048)
			(end -0.67945 0.3048)
			(stroke
				(width 0.1)
				(type default)
			)
			(layer "F.Fab")
		)
		(fp_line
			(start 0.120396 0.3048)
			(end 0.120396 0.2794)
			(stroke
				(width 0.1)
				(type default)
			)
			(layer "F.Fab")
		)
		(fp_line
			(start 0.67945 0.3048)
			(end 0.120396 0.3048)
			(stroke
				(width 0.1)
				(type default)
			)
			(layer "F.Fab")
		)
		(fp_line
			(start -0.12065 0.2794)
			(end -0.12065 0.3048)
			(stroke
				(width 0.1)
				(type default)
			)
			(layer "F.Fab")
		)
		(fp_line
			(start 0.120396 0.2794)
			(end -0.12065 0.2794)
			(stroke
				(width 0.1)
				(type default)
			)
			(layer "F.Fab")
		)
		(fp_line
			(start -0.12065 -0.2794)
			(end 0.12065 -0.2794)
			(stroke
				(width 0.1)
				(type default)
			)
			(layer "F.Fab")
		)
		(fp_line
			(start 0.12065 -0.2794)
			(end 0.12065 -0.3048)
			(stroke
				(width 0.1)
				(type default)
			)
			(layer "F.Fab")
		)
		(fp_line
			(start 0.12065 -0.3048)
			(end 0.67945 -0.3048)
			(stroke
				(width 0.1)
				(type default)
			)
			(layer "F.Fab")
		)
		(fp_line
			(start 0.67945 -0.3048)
			(end 0.67945 0.3048)
			(stroke
				(width 0.1)
				(type default)
			)
			(layer "F.Fab")
		)
		(fp_line
			(start -0.67945 -0.305054)
			(end -0.12065 -0.305054)
			(stroke
				(width 0.1)
				(type default)
			)
			(layer "F.Fab")
		)
		(fp_line
			(start -0.12065 -0.305054)
			(end -0.12065 -0.2794)
			(stroke
				(width 0.1)
				(type default)
			)
			(layer "F.Fab")
		)
		(pad "1" smd circle
			(at -0.40005 0 270)
			(size 0 0)
			(layers "F.Cu" "F.Mask" "F.Paste")
			(net "VCCIO2")
		)
		(pad "2" smd circle
			(at 0.40005 0 270)
			(size 0 0)
			(layers "F.Cu" "F.Mask" "F.Paste")
			(net "PU_PB25A")
		)
	)
	(footprint ""
		(layer "F.Cu")
		(at 29.845 -19.558 180)
		(property "Reference" "Q2"
			(at 2.921 -1.305052 0)
			(unlocked yes)
			(layer "F.SilkS")
			(effects
				(font
					(size 0.7874 0.5842)
					(thickness 0.1524)
				)
				(justify left)
			)
		)
		(property "Value" ""
			(at 0 0 180)
			(layer "F.Fab")
			(effects
				(font
					(size 1.27 1.27)
				)
			)
		)
		(duplicate_pad_numbers_are_jumpers no)
		(fp_line
			(start 1.332738 1.100074)
			(end -1.332738 1.100074)
			(stroke
				(width 0.1524)
				(type default)
			)
			(layer "F.SilkS")
		)
		(fp_line
			(start 1.332738 -1.100074)
			(end 1.332738 1.100074)
			(stroke
				(width 0.1524)
				(type default)
			)
			(layer "F.SilkS")
		)
		(fp_line
			(start 0.4826 -1.100074)
			(end 1.332738 -1.100074)
			(stroke
				(width 0.1524)
				(type default)
			)
			(layer "F.SilkS")
		)
		(fp_line
			(start 0 -0.541274)
			(end 0.4826 -1.100074)
			(stroke
				(width 0.1524)
				(type default)
			)
			(layer "F.SilkS")
		)
		(fp_line
			(start -0.4826 -1.100074)
			(end 0 -0.541274)
			(stroke
				(width 0.1524)
				(type default)
			)
			(layer "F.SilkS")
		)
		(fp_line
			(start -1.332738 1.100074)
			(end -1.332738 -1.100074)
			(stroke
				(width 0.1524)
				(type default)
			)
			(layer "F.SilkS")
		)
		(fp_line
			(start -1.332738 -1.100074)
			(end -0.4826 -1.100074)
			(stroke
				(width 0.1524)
				(type default)
			)
			(layer "F.SilkS")
		)
		(fp_poly
			(pts
				(xy -2.2352 -0.298958) (xy -2.2352 -1.001014) (xy -1.533144 -0.649986)
			)
			(stroke
				(width 0)
				(type default)
			)
			(fill yes)
			(layer "F.SilkS")
		)
		(fp_line
			(start 0.674878 1.100074)
			(end -0.674878 1.100074)
			(stroke
				(width 0.1)
				(type default)
			)
			(layer "F.Fab")
		)
		(fp_line
			(start 0.674878 -1.100074)
			(end 0.674878 1.100074)
			(stroke
				(width 0.1)
				(type default)
			)
			(layer "F.Fab")
		)
		(fp_line
			(start -0.674878 1.100074)
			(end -0.674878 -1.100074)
			(stroke
				(width 0.1)
				(type default)
			)
			(layer "F.Fab")
		)
		(fp_line
			(start -0.674878 -1.100074)
			(end 0.674878 -1.100074)
			(stroke
				(width 0.1)
				(type default)
			)
			(layer "F.Fab")
		)
		(fp_poly
			(pts
				(xy -2.2352 -0.298958) (xy -2.2352 -1.001014) (xy -1.533144 -0.649986)
			)
			(stroke
				(width 0)
				(type default)
			)
			(fill yes)
			(layer "F.Fab")
		)
		(pad "1" smd rect
			(at -0.94996 -0.649986 270)
			(size 0.4318 0.508)
			(layers "F.Cu" "F.Mask" "F.Paste")
			(net "V_BMC_DDC_SDA")
		)
		(pad "2" smd rect
			(at -0.94996 0 270)
			(size 0.4318 0.508)
			(layers "F.Cu" "F.Mask" "F.Paste")
			(net "V_BMC_DDC_LS_GATE")
		)
		(pad "3" smd rect
			(at -0.94996 0.649986 270)
			(size 0.4318 0.508)
			(layers "F.Cu" "F.Mask" "F.Paste")
			(net "V_BMC_LS_DDC_SCL")
		)
		(pad "4" smd rect
			(at 0.94996 0.649986 270)
			(size 0.4318 0.508)
			(layers "F.Cu" "F.Mask" "F.Paste")
			(net "V_BMC_DDC_SCL")
		)
		(pad "5" smd rect
			(at 0.94996 0 270)
			(size 0.4318 0.508)
			(layers "F.Cu" "F.Mask" "F.Paste")
			(net "V_BMC_DDC_LS_GATE")
		)
		(pad "6" smd rect
			(at 0.94996 -0.649986 270)
			(size 0.4318 0.508)
			(layers "F.Cu" "F.Mask" "F.Paste")
			(net "V_BMC_LS_DDC_SDA")
		)
	)
	(footprint ""
		(layer "F.Cu")
		(at 39.805102 -65.793366 90)
		(property "Reference" "R199"
			(at 0 0 90)
			(layer "F.SilkS")
			(hide yes)
			(effects
				(font
					(size 1.27 1.27)
				)
			)
		)
		(property "Value" ""
			(at 0 0 90)
			(layer "F.Fab")
			(effects
				(font
					(size 1.27 1.27)
				)
			)
		)
		(duplicate_pad_numbers_are_jumpers no)
		(fp_line
			(start 0.7874 -0.4064)
			(end 0.7874 0.4064)
			(stroke
				(width 0.1524)
				(type default)
			)
			(layer "F.SilkS")
		)
		(fp_line
			(start -0.7874 -0.4064)
			(end 0.7874 -0.4064)
			(stroke
				(width 0.1524)
				(type default)
			)
			(layer "F.SilkS")
		)
		(fp_line
			(start 0.7874 0.4064)
			(end -0.7874 0.4064)
			(stroke
				(width 0.1524)
				(type default)
			)
			(layer "F.SilkS")
		)
		(fp_line
			(start -0.7874 0.4064)
			(end -0.7874 -0.4064)
			(stroke
				(width 0.1524)
				(type default)
			)
			(layer "F.SilkS")
		)
		(fp_line
			(start -0.12065 -0.305054)
			(end -0.12065 -0.2794)
			(stroke
				(width 0.1)
				(type default)
			)
			(layer "F.Fab")
		)
		(fp_line
			(start -0.67945 -0.305054)
			(end -0.12065 -0.305054)
			(stroke
				(width 0.1)
				(type default)
			)
			(layer "F.Fab")
		)
		(fp_line
			(start 0.67945 -0.3048)
			(end 0.67945 0.3048)
			(stroke
				(width 0.1)
				(type default)
			)
			(layer "F.Fab")
		)
		(fp_line
			(start 0.12065 -0.3048)
			(end 0.67945 -0.3048)
			(stroke
				(width 0.1)
				(type default)
			)
			(layer "F.Fab")
		)
		(fp_line
			(start 0.12065 -0.2794)
			(end 0.12065 -0.3048)
			(stroke
				(width 0.1)
				(type default)
			)
			(layer "F.Fab")
		)
		(fp_line
			(start -0.12065 -0.2794)
			(end 0.12065 -0.2794)
			(stroke
				(width 0.1)
				(type default)
			)
			(layer "F.Fab")
		)
		(fp_line
			(start 0.120396 0.2794)
			(end -0.12065 0.2794)
			(stroke
				(width 0.1)
				(type default)
			)
			(layer "F.Fab")
		)
		(fp_line
			(start -0.12065 0.2794)
			(end -0.12065 0.3048)
			(stroke
				(width 0.1)
				(type default)
			)
			(layer "F.Fab")
		)
		(fp_line
			(start 0.67945 0.3048)
			(end 0.120396 0.3048)
			(stroke
				(width 0.1)
				(type default)
			)
			(layer "F.Fab")
		)
		(fp_line
			(start 0.120396 0.3048)
			(end 0.120396 0.2794)
			(stroke
				(width 0.1)
				(type default)
			)
			(layer "F.Fab")
		)
		(fp_line
			(start -0.12065 0.3048)
			(end -0.67945 0.3048)
			(stroke
				(width 0.1)
				(type default)
			)
			(layer "F.Fab")
		)
		(fp_line
			(start -0.67945 0.3048)
			(end -0.67945 -0.305054)
			(stroke
				(width 0.1)
				(type default)
			)
			(layer "F.Fab")
		)
		(pad "1" smd circle
			(at -0.40005 0 90)
			(size 0 0)
			(layers "F.Cu" "F.Mask" "F.Paste")
			(net "I3C3_SDA_R")
		)
		(pad "2" smd circle
			(at 0.40005 0 90)
			(size 0 0)
			(layers "F.Cu" "F.Mask" "F.Paste")
			(net "I3C3_SPD_SDA")
		)
	)
	(footprint ""
		(layer "F.Cu")
		(at 3.0734 -111.45266)
		(property "Reference" ""
			(at 0 0 0)
			(layer "F.SilkS")
			(hide yes)
			(effects
				(font
					(size 1.27 1.27)
				)
			)
		)
		(property "Value" ""
			(at 0 0 0)
			(layer "F.Fab")
			(effects
				(font
					(size 1.27 1.27)
				)
			)
		)
		(duplicate_pad_numbers_are_jumpers no)
		(pad "1" smd circle
			(at 0 0)
			(size 0.9906 0.9906)
			(layers "F.Cu" "F.Mask" "F.Paste")
			(net "Net_324")
		)
		(zone
			(layer "F.Cu")
			(hatch none 0.5)
			(connect_pads
				(clearance 0)
			)
			(min_thickness 0.25)
			(keepout
				(tracks not_allowed)
				(vias allowed)
				(pads allowed)
				(copperpour not_allowed)
				(footprints allowed)
			)
			(placement
				(enabled no)
				(sheetname "")
			)
			(fill
				(thermal_gap 0.5)
				(thermal_bridge_width 0.5)
				(island_removal_mode 0)
			)
			(polygon
				(pts
					(arc
						(start 4.699 -111.45266)
						(mid 1.4478 -111.45266)
						(end 4.699 -111.45266)
					)
				)
			)
		)
	)
	(footprint ""
		(layer "F.Cu")
		(at 16.256 -33.4518 -90)
		(property "Reference" "C302"
			(at 0 0 270)
			(layer "F.SilkS")
			(hide yes)
			(effects
				(font
					(size 1.27 1.27)
				)
			)
		)
		(property "Value" ""
			(at 0 0 270)
			(layer "F.Fab")
			(effects
				(font
					(size 1.27 1.27)
				)
			)
		)
		(duplicate_pad_numbers_are_jumpers no)
		(fp_line
			(start -0.7874 0.4064)
			(end -0.7874 -0.4064)
			(stroke
				(width 0.1524)
				(type default)
			)
			(layer "F.SilkS")
		)
		(fp_line
			(start 0.7874 0.4064)
			(end -0.7874 0.4064)
			(stroke
				(width 0.1524)
				(type default)
			)
			(layer "F.SilkS")
		)
		(fp_line
			(start -0.7874 -0.4064)
			(end 0.7874 -0.4064)
			(stroke
				(width 0.1524)
				(type default)
			)
			(layer "F.SilkS")
		)
		(fp_line
			(start 0.7874 -0.4064)
			(end 0.7874 0.4064)
			(stroke
				(width 0.1524)
				(type default)
			)
			(layer "F.SilkS")
		)
		(fp_line
			(start -0.67945 0.3048)
			(end -0.67945 -0.305054)
			(stroke
				(width 0.1)
				(type default)
			)
			(layer "F.Fab")
		)
		(fp_line
			(start -0.12065 0.3048)
			(end -0.67945 0.3048)
			(stroke
				(width 0.1)
				(type default)
			)
			(layer "F.Fab")
		)
		(fp_line
			(start 0.120396 0.3048)
			(end 0.120396 0.2794)
			(stroke
				(width 0.1)
				(type default)
			)
			(layer "F.Fab")
		)
		(fp_line
			(start 0.67945 0.3048)
			(end 0.120396 0.3048)
			(stroke
				(width 0.1)
				(type default)
			)
			(layer "F.Fab")
		)
		(fp_line
			(start -0.12065 0.2794)
			(end -0.12065 0.3048)
			(stroke
				(width 0.1)
				(type default)
			)
			(layer "F.Fab")
		)
		(fp_line
			(start 0.120396 0.2794)
			(end -0.12065 0.2794)
			(stroke
				(width 0.1)
				(type default)
			)
			(layer "F.Fab")
		)
		(fp_line
			(start -0.12065 -0.2794)
			(end 0.12065 -0.2794)
			(stroke
				(width 0.1)
				(type default)
			)
			(layer "F.Fab")
		)
		(fp_line
			(start 0.12065 -0.2794)
			(end 0.12065 -0.3048)
			(stroke
				(width 0.1)
				(type default)
			)
			(layer "F.Fab")
		)
		(fp_line
			(start 0.12065 -0.3048)
			(end 0.67945 -0.3048)
			(stroke
				(width 0.1)
				(type default)
			)
			(layer "F.Fab")
		)
		(fp_line
			(start 0.67945 -0.3048)
			(end 0.67945 0.3048)
			(stroke
				(width 0.1)
				(type default)
			)
			(layer "F.Fab")
		)
		(fp_line
			(start -0.67945 -0.305054)
			(end -0.12065 -0.305054)
			(stroke
				(width 0.1)
				(type default)
			)
			(layer "F.Fab")
		)
		(fp_line
			(start -0.12065 -0.305054)
			(end -0.12065 -0.2794)
			(stroke
				(width 0.1)
				(type default)
			)
			(layer "F.Fab")
		)
		(pad "1" smd circle
			(at -0.40005 0 270)
			(size 0 0)
			(layers "F.Cu" "F.Mask" "F.Paste")
			(net "P3V3_LDO")
		)
		(pad "2" smd circle
			(at 0.40005 0 270)
			(size 0 0)
			(layers "F.Cu" "F.Mask" "F.Paste")
			(net "GND")
		)
	)
)
